(kicad_pcb
	(version 20260206)
	(generator "pcbnew")
	(generator_version "10.0")
	(general
		(thickness 1.6)
		(legacy_teardrops no)
	)
	(paper "A4")
	(title_block
		(title "Bryce Canyon_IOM_M2_16342-2_OCP.brd")
		(comment 1 "Bryce Canyon / footprints 131-138 of 1146")
	)
	(layers
		(0 "F.Cu" signal "TOP")
		(4 "In1.Cu" signal "L2GND")
		(6 "In2.Cu" signal "L3")
		(8 "In3.Cu" signal "L4VCC")
		(10 "In4.Cu" signal "L5VCC")
		(12 "In5.Cu" signal "L6")
		(14 "In6.Cu" signal "L7GND")
		(2 "B.Cu" signal "BOTTOM")
		(9 "F.Adhes" user "F.Adhesive")
		(11 "B.Adhes" user "B.Adhesive")
		(13 "F.Paste" user "Package Geometry/Pastemask Top")
		(15 "B.Paste" user "Package Geometry/Pastemask Bottom")
		(5 "F.SilkS" user "Ref Des/Silkscreen Top")
		(7 "B.SilkS" user "Ref Des/Silkscreen Bottom")
		(1 "F.Mask" user "Board Geometry/Soldermask Top")
		(3 "B.Mask" user "Board Geometry/Soldermask Bottom")
		(17 "Dwgs.User" user "User.Drawings")
		(19 "Cmts.User" user "User.Comments")
		(21 "Eco1.User" user "User.Eco1")
		(23 "Eco2.User" user "User.Eco2")
		(25 "Edge.Cuts" user "Board Geometry/Outline")
		(27 "Margin" user)
		(31 "F.CrtYd" user "Package Geometry/Place Bound Top")
		(29 "B.CrtYd" user "Package Geometry/Place Bound Bottom")
		(35 "F.Fab" user "Ref Des/Assembly Top")
		(33 "B.Fab" user "Ref Des/Assembly Bottom")
	)
	(footprint ""
		(layer "F.Cu")
		(at 66.364104 -170.111674 90)
		(property "Reference" "R80"
			(at 0 0 90)
			(layer "F.SilkS")
			(hide yes)
			(effects
				(font
					(size 1.27 1.27)
				)
			)
		)
		(property "Value" "100KR2F-L1-GP"
			(at 0.064008 -3.993896 90)
			(unlocked yes)
			(layer "F.Fab")
			(hide yes)
			(effects
				(font
					(size 1.016 1.016)
					(thickness 0.1524)
				)
			)
		)
		(property "Device Type" "R402H16"
			(at 0.064008 -5.517896 90)
			(unlocked yes)
			(layer "F.Fab")
			(hide yes)
			(effects
				(font
					(size 1.016 1.016)
					(thickness 0.1524)
				)
			)
		)
		(duplicate_pad_numbers_are_jumpers no)
		(fp_line
			(start 0.508 -0.9398)
			(end -0.508 -0.9398)
			(stroke
				(width 0.1524)
				(type default)
			)
			(layer "F.SilkS")
		)
		(fp_line
			(start -0.508 -0.9398)
			(end -0.508 0.9398)
			(stroke
				(width 0.1524)
				(type default)
			)
			(layer "F.SilkS")
		)
		(fp_rect
			(start -0.508 0.9398)
			(end 0.508 -0.9398)
			(stroke
				(width 0)
				(type default)
			)
			(fill no)
			(layer "F.CrtYd")
		)
		(fp_rect
			(start -0.508 0.9398)
			(end 0.508 -0.9398)
			(stroke
				(width 0)
				(type default)
			)
			(fill no)
			(layer "F.Fab")
		)
		(pad "1" smd custom
			(at 0 -0.4445 90)
			(size 0.1397 0.1397)
			(layers "F.Cu" "F.Mask" "F.Paste")
			(net "Q4_G")
			(options
				(clearance outline)
				(anchor circle)
			)
			(primitives
				(gr_poly
					(pts
						(arc
							(start -0.1778 -0.2794)
							(mid -0.249642 -0.249642)
							(end -0.2794 -0.1778)
						)
						(arc
							(start -0.2794 0.1778)
							(mid -0.249642 0.249642)
							(end -0.1778 0.2794)
						)
						(arc
							(start 0.1778 0.2794)
							(mid 0.249642 0.249642)
							(end 0.2794 0.1778)
						)
						(arc
							(start 0.2794 -0.1778)
							(mid 0.249642 -0.249642)
							(end 0.1778 -0.2794)
						)
					)
					(width 0)
					(fill yes)
				)
			)
		)
		(pad "2" smd custom
			(at 0 0.4445 90)
			(size 0.1397 0.1397)
			(layers "F.Cu" "F.Mask" "F.Paste")
			(net "GND")
			(options
				(clearance outline)
				(anchor circle)
			)
			(primitives
				(gr_poly
					(pts
						(arc
							(start -0.1778 -0.2794)
							(mid -0.249642 -0.249642)
							(end -0.2794 -0.1778)
						)
						(arc
							(start -0.2794 0.1778)
							(mid -0.249642 0.249642)
							(end -0.1778 0.2794)
						)
						(arc
							(start 0.1778 0.2794)
							(mid 0.249642 0.249642)
							(end 0.2794 0.1778)
						)
						(arc
							(start 0.2794 -0.1778)
							(mid 0.249642 -0.249642)
							(end 0.1778 -0.2794)
						)
					)
					(width 0)
					(fill yes)
				)
			)
		)
	)
	(footprint ""
		(layer "F.Cu")
		(at 216.642188 -37.976556 -90)
		(property "Reference" "R468"
			(at 0 0 270)
			(layer "F.SilkS")
			(hide yes)
			(effects
				(font
					(size 1.27 1.27)
				)
			)
		)
		(property "Value" "3K3R2J-3-GP"
			(at 0.064008 -3.993896 270)
			(unlocked yes)
			(layer "F.Fab")
			(hide yes)
			(effects
				(font
					(size 1.016 1.016)
					(thickness 0.1524)
				)
			)
		)
		(property "Device Type" "R402H16"
			(at 0.064008 -5.517896 270)
			(unlocked yes)
			(layer "F.Fab")
			(hide yes)
			(effects
				(font
					(size 1.016 1.016)
					(thickness 0.1524)
				)
			)
		)
		(duplicate_pad_numbers_are_jumpers no)
		(fp_line
			(start -0.508 -0.9398)
			(end -0.508 0.9398)
			(stroke
				(width 0.1524)
				(type default)
			)
			(layer "F.SilkS")
		)
		(fp_line
			(start 0.508 -0.9398)
			(end -0.508 -0.9398)
			(stroke
				(width 0.1524)
				(type default)
			)
			(layer "F.SilkS")
		)
		(fp_rect
			(start -0.508 0.9398)
			(end 0.508 -0.9398)
			(stroke
				(width 0)
				(type default)
			)
			(fill no)
			(layer "F.CrtYd")
		)
		(fp_rect
			(start -0.508 0.9398)
			(end 0.508 -0.9398)
			(stroke
				(width 0)
				(type default)
			)
			(fill no)
			(layer "F.Fab")
		)
		(pad "1" smd custom
			(at 0 -0.4445 270)
			(size 0.1397 0.1397)
			(layers "F.Cu" "F.Mask" "F.Paste")
			(net "P5V_LL")
			(options
				(clearance outline)
				(anchor circle)
			)
			(primitives
				(gr_poly
					(pts
						(arc
							(start -0.1778 -0.2794)
							(mid -0.249642 -0.249642)
							(end -0.2794 -0.1778)
						)
						(arc
							(start -0.2794 0.1778)
							(mid -0.249642 0.249642)
							(end -0.1778 0.2794)
						)
						(arc
							(start 0.1778 0.2794)
							(mid 0.249642 0.249642)
							(end 0.2794 0.1778)
						)
						(arc
							(start 0.2794 -0.1778)
							(mid 0.249642 -0.249642)
							(end 0.1778 -0.2794)
						)
					)
					(width 0)
					(fill yes)
				)
			)
		)
		(pad "2" smd custom
			(at 0 0.4445 270)
			(size 0.1397 0.1397)
			(layers "F.Cu" "F.Mask" "F.Paste")
			(net "P5V_LL_R")
			(options
				(clearance outline)
				(anchor circle)
			)
			(primitives
				(gr_poly
					(pts
						(arc
							(start -0.1778 -0.2794)
							(mid -0.249642 -0.249642)
							(end -0.2794 -0.1778)
						)
						(arc
							(start -0.2794 0.1778)
							(mid -0.249642 0.249642)
							(end -0.1778 0.2794)
						)
						(arc
							(start 0.1778 0.2794)
							(mid 0.249642 0.249642)
							(end 0.2794 0.1778)
						)
						(arc
							(start 0.2794 -0.1778)
							(mid 0.249642 -0.249642)
							(end 0.1778 -0.2794)
						)
					)
					(width 0)
					(fill yes)
				)
			)
		)
	)
	(footprint ""
		(layer "F.Cu")
		(at 33.693354 -186.99861)
		(property "Reference" "R490"
			(at 0 0 0)
			(layer "F.SilkS")
			(hide yes)
			(effects
				(font
					(size 1.27 1.27)
				)
			)
		)
		(property "Value" "3D01R5F-GP"
			(at 0 -8.9535 0)
			(unlocked yes)
			(layer "F.Fab")
			(hide yes)
			(effects
				(font
					(size 1.27 1.016)
					(thickness 0.1524)
				)
			)
		)
		(property "Device Type" "R805H24"
			(at 0 -10.6299 0)
			(unlocked yes)
			(layer "F.Fab")
			(hide yes)
			(effects
				(font
					(size 1.27 1.016)
					(thickness 0.1524)
				)
			)
		)
		(duplicate_pad_numbers_are_jumpers no)
		(fp_line
			(start -0.889 -1.7018)
			(end -0.889 0.2794)
			(stroke
				(width 0.1524)
				(type default)
			)
			(layer "F.SilkS")
		)
		(fp_line
			(start -0.889 0.0762)
			(end -0.889 1.7018)
			(stroke
				(width 0.1524)
				(type default)
			)
			(layer "F.SilkS")
		)
		(fp_line
			(start -0.889 1.7018)
			(end 0.889 1.7018)
			(stroke
				(width 0.1524)
				(type default)
			)
			(layer "F.SilkS")
		)
		(fp_line
			(start 0.889 -1.7018)
			(end -0.889 -1.7018)
			(stroke
				(width 0.1524)
				(type default)
			)
			(layer "F.SilkS")
		)
		(fp_line
			(start 0.889 -1.7018)
			(end 0.889 -0.381)
			(stroke
				(width 0.1524)
				(type default)
			)
			(layer "F.SilkS")
		)
		(fp_line
			(start 0.889 1.7018)
			(end 0.889 -0.508)
			(stroke
				(width 0.1524)
				(type default)
			)
			(layer "F.SilkS")
		)
		(fp_poly
			(pts
				(xy 0.9652 -1.778) (xy 0.9652 1.778) (xy -0.9652 1.778) (xy -0.9652 -1.778)
			)
			(stroke
				(width 0)
				(type default)
			)
			(fill no)
			(layer "F.CrtYd")
		)
		(fp_rect
			(start -0.9652 1.778)
			(end 0.9652 -1.778)
			(stroke
				(width 0)
				(type default)
			)
			(fill no)
			(layer "F.Fab")
		)
		(pad "1" smd rect
			(at 0 -0.9652)
			(size 1.397 1.143)
			(layers "F.Cu" "F.Mask" "F.Paste")
			(net "P3V3_SNB")
		)
		(pad "2" smd rect
			(at 0 0.9652)
			(size 1.397 1.143)
			(layers "F.Cu" "F.Mask" "F.Paste")
			(net "GND")
		)
	)
	(footprint ""
		(layer "F.Cu")
		(at 153.986738 -7.697978 -90)
		(property "Reference" "C213"
			(at 0 0 270)
			(layer "F.SilkS")
			(hide yes)
			(effects
				(font
					(size 1.27 1.27)
				)
			)
		)
		(property "Value" "SC1U16V3KX-5GP"
			(at 0 -2.8194 270)
			(unlocked yes)
			(layer "F.Fab")
			(hide yes)
			(effects
				(font
					(size 1.016 1.016)
					(thickness 0.1524)
				)
			)
		)
		(property "Device Type" "C603H36"
			(at 0 -4.3434 270)
			(unlocked yes)
			(layer "F.Fab")
			(hide yes)
			(effects
				(font
					(size 1.016 1.016)
					(thickness 0.1524)
				)
			)
		)
		(duplicate_pad_numbers_are_jumpers no)
		(fp_line
			(start 0.508 0)
			(end -0.508 0)
			(stroke
				(width 0.2032)
				(type default)
			)
			(layer "F.SilkS")
		)
		(fp_rect
			(start -0.5842 1.3335)
			(end 0.5842 -1.3335)
			(stroke
				(width 0)
				(type default)
			)
			(fill no)
			(layer "F.CrtYd")
		)
		(fp_rect
			(start -0.5842 1.3335)
			(end 0.5842 -1.3335)
			(stroke
				(width 0)
				(type default)
			)
			(fill no)
			(layer "F.Fab")
		)
		(pad "1" smd custom
			(at 0 -0.762 270)
			(size 0.2159 0.2159)
			(layers "F.Cu" "F.Mask" "F.Paste")
			(net "GND")
			(options
				(clearance outline)
				(anchor circle)
			)
			(primitives
				(gr_poly
					(pts
						(arc
							(start -0.3302 -0.4318)
							(mid -0.402042 -0.402042)
							(end -0.4318 -0.3302)
						)
						(arc
							(start -0.4318 0.3302)
							(mid -0.402042 0.402042)
							(end -0.3302 0.4318)
						)
						(arc
							(start 0.3302 0.4318)
							(mid 0.402042 0.402042)
							(end 0.4318 0.3302)
						)
						(arc
							(start 0.4318 -0.3302)
							(mid 0.402042 -0.402042)
							(end 0.3302 -0.4318)
						)
					)
					(width 0)
					(fill yes)
				)
			)
		)
		(pad "2" smd custom
			(at 0 0.762 270)
			(size 0.2159 0.2159)
			(layers "F.Cu" "F.Mask" "F.Paste")
			(net "P1V8_STBY_EN_R")
			(options
				(clearance outline)
				(anchor circle)
			)
			(primitives
				(gr_poly
					(pts
						(arc
							(start -0.3302 -0.4318)
							(mid -0.402042 -0.402042)
							(end -0.4318 -0.3302)
						)
						(arc
							(start -0.4318 0.3302)
							(mid -0.402042 0.402042)
							(end -0.3302 0.4318)
						)
						(arc
							(start 0.3302 0.4318)
							(mid 0.402042 0.402042)
							(end 0.4318 0.3302)
						)
						(arc
							(start 0.4318 -0.3302)
							(mid 0.402042 -0.402042)
							(end 0.3302 -0.4318)
						)
					)
					(width 0)
					(fill yes)
				)
			)
		)
	)
	(footprint ""
		(layer "F.Cu")
		(at 215.17864 -102.615492 90)
		(property "Reference" "R824"
			(at 0 0 90)
			(layer "F.SilkS")
			(hide yes)
			(effects
				(font
					(size 1.27 1.27)
				)
			)
		)
		(property "Value" "39K2R2F-L-GP"
			(at 0.064008 -3.993896 90)
			(unlocked yes)
			(layer "F.Fab")
			(hide yes)
			(effects
				(font
					(size 1.016 1.016)
					(thickness 0.1524)
				)
			)
		)
		(property "Device Type" "R402H16"
			(at 0.064008 -5.517896 90)
			(unlocked yes)
			(layer "F.Fab")
			(hide yes)
			(effects
				(font
					(size 1.016 1.016)
					(thickness 0.1524)
				)
			)
		)
		(duplicate_pad_numbers_are_jumpers no)
		(fp_line
			(start 0.508 -0.9398)
			(end -0.508 -0.9398)
			(stroke
				(width 0.1524)
				(type default)
			)
			(layer "F.SilkS")
		)
		(fp_line
			(start -0.508 -0.9398)
			(end -0.508 0.9398)
			(stroke
				(width 0.1524)
				(type default)
			)
			(layer "F.SilkS")
		)
		(fp_rect
			(start -0.508 0.9398)
			(end 0.508 -0.9398)
			(stroke
				(width 0)
				(type default)
			)
			(fill no)
			(layer "F.CrtYd")
		)
		(fp_rect
			(start -0.508 0.9398)
			(end 0.508 -0.9398)
			(stroke
				(width 0)
				(type default)
			)
			(fill no)
			(layer "F.Fab")
		)
		(pad "1" smd custom
			(at 0 -0.4445 90)
			(size 0.1397 0.1397)
			(layers "F.Cu" "F.Mask" "F.Paste")
			(net "AGND_P3V3_M2")
			(options
				(clearance outline)
				(anchor circle)
			)
			(primitives
				(gr_poly
					(pts
						(arc
							(start -0.1778 -0.2794)
							(mid -0.249642 -0.249642)
							(end -0.2794 -0.1778)
						)
						(arc
							(start -0.2794 0.1778)
							(mid -0.249642 0.249642)
							(end -0.1778 0.2794)
						)
						(arc
							(start 0.1778 0.2794)
							(mid 0.249642 0.249642)
							(end 0.2794 0.1778)
						)
						(arc
							(start 0.2794 -0.1778)
							(mid 0.249642 -0.249642)
							(end 0.1778 -0.2794)
						)
					)
					(width 0)
					(fill yes)
				)
			)
		)
		(pad "2" smd custom
			(at 0 0.4445 90)
			(size 0.1397 0.1397)
			(layers "F.Cu" "F.Mask" "F.Paste")
			(net "P3V3_M2_MODE")
			(options
				(clearance outline)
				(anchor circle)
			)
			(primitives
				(gr_poly
					(pts
						(arc
							(start -0.1778 -0.2794)
							(mid -0.249642 -0.249642)
							(end -0.2794 -0.1778)
						)
						(arc
							(start -0.2794 0.1778)
							(mid -0.249642 0.249642)
							(end -0.1778 0.2794)
						)
						(arc
							(start 0.1778 0.2794)
							(mid 0.249642 0.249642)
							(end 0.2794 0.1778)
						)
						(arc
							(start 0.2794 -0.1778)
							(mid 0.249642 -0.249642)
							(end 0.1778 -0.2794)
						)
					)
					(width 0)
					(fill yes)
				)
			)
		)
	)
	(footprint ""
		(layer "F.Cu")
		(at 78.122018 -77.353668 90)
		(property "Reference" "VIA3"
			(at 0 0 90)
			(layer "F.SilkS")
			(hide yes)
			(effects
				(font
					(size 1.27 1.27)
				)
			)
		)
		(property "Value" "85OHM-8L-1D6MM-L16L18-GP"
			(at 4.064 0.6096 90)
			(unlocked yes)
			(layer "F.Fab")
			(hide yes)
			(effects
				(font
					(size 1.016 1.016)
					(thickness 0.1524)
				)
			)
		)
		(property "Device Type" "VIA-PCIE-4P-368076"
			(at 4.064 -0.9144 90)
			(unlocked yes)
			(layer "F.Fab")
			(hide yes)
			(effects
				(font
					(size 1.016 1.016)
					(thickness 0.1524)
				)
			)
		)
		(duplicate_pad_numbers_are_jumpers no)
		(fp_rect
			(start -1.8415 0.381)
			(end 1.8415 -0.381)
			(stroke
				(width 0)
				(type default)
			)
			(fill no)
			(layer "F.CrtYd")
		)
		(fp_rect
			(start -1.8415 0.381)
			(end 1.8415 -0.381)
			(stroke
				(width 0)
				(type default)
			)
			(fill no)
			(layer "F.Fab")
		)
		(pad "1" thru_hole circle
			(at -1.4605 0 90)
			(size 0.508 0.508)
			(drill 0.254)
			(layers "*.Cu" "*.Mask")
			(remove_unused_layers no)
			(net "GND")
			(clearance 0.127)
			(thermal_gap 0.127)
		)
		(pad "2" thru_hole circle
			(at -0.4445 0 90)
			(size 0.508 0.508)
			(drill 0.254)
			(layers "*.Cu" "*.Mask")
			(remove_unused_layers no)
			(net "PCIE_COMP_TO_IOM_18_DP")
			(clearance 0.127)
			(thermal_gap 0.127)
		)
		(pad "3" thru_hole circle
			(at 0.4445 0 90)
			(size 0.508 0.508)
			(drill 0.254)
			(layers "*.Cu" "*.Mask")
			(remove_unused_layers no)
			(net "PCIE_COMP_TO_IOM_18_DN")
			(clearance 0.127)
			(thermal_gap 0.127)
		)
		(pad "4" thru_hole circle
			(at 1.4605 0 90)
			(size 0.508 0.508)
			(drill 0.254)
			(layers "*.Cu" "*.Mask")
			(remove_unused_layers no)
			(net "GND")
			(clearance 0.127)
			(thermal_gap 0.127)
		)
	)
	(footprint ""
		(layer "F.Cu")
		(at 205.232 -141.224 -135)
		(property "Reference" "VIA52"
			(at 0 0 225)
			(layer "F.SilkS")
			(hide yes)
			(effects
				(font
					(size 1.27 1.27)
				)
			)
		)
		(property "Value" "85OHM-8L-1D6MM-L16L18-GP"
			(at 4.064105 0.609655 225)
			(unlocked yes)
			(layer "F.Fab")
			(hide yes)
			(effects
				(font
					(size 1.016 1.016)
					(thickness 0.1524)
				)
			)
		)
		(property "Device Type" "VIA-PCIE-4P-368076"
			(at 4.064105 -0.914474 225)
			(unlocked yes)
			(layer "F.Fab")
			(hide yes)
			(effects
				(font
					(size 1.016 1.016)
					(thickness 0.1524)
				)
			)
		)
		(duplicate_pad_numbers_are_jumpers no)
		(fp_poly
			(pts
				(xy -1.841491 -0.381057) (xy 1.841509 -0.381058) (xy 1.841508 0.380942) (xy -1.841491 0.380942)
			)
			(stroke
				(width 0)
				(type default)
			)
			(fill no)
			(layer "F.CrtYd")
		)
		(fp_poly
			(pts
				(xy -1.841491 -0.381057) (xy 1.841509 -0.381058) (xy 1.841508 0.380942) (xy -1.841491 0.380942)
			)
			(stroke
				(width 0)
				(type default)
			)
			(fill no)
			(layer "F.Fab")
		)
		(pad "1" thru_hole circle
			(at -1.460499 0 225)
			(size 0.508 0.508)
			(drill 0.254)
			(layers "*.Cu" "*.Mask")
			(remove_unused_layers no)
			(net "GND")
			(clearance 0.127)
			(thermal_gap 0.127)
		)
		(pad "2" thru_hole circle
			(at -0.4445 0 225)
			(size 0.508 0.508)
			(drill 0.254)
			(layers "*.Cu" "*.Mask")
			(remove_unused_layers no)
			(net "PCIE_COMP_TO_IOM_9_DP")
			(clearance 0.127)
			(thermal_gap 0.127)
		)
		(pad "3" thru_hole circle
			(at 0.4445 0 225)
			(size 0.508 0.508)
			(drill 0.254)
			(layers "*.Cu" "*.Mask")
			(remove_unused_layers no)
			(net "PCIE_COMP_TO_IOM_9_DN")
			(clearance 0.127)
			(thermal_gap 0.127)
		)
		(pad "4" thru_hole circle
			(at 1.460499 0 225)
			(size 0.508 0.508)
			(drill 0.254)
			(layers "*.Cu" "*.Mask")
			(remove_unused_layers no)
			(net "GND")
			(clearance 0.127)
			(thermal_gap 0.127)
		)
	)
	(footprint ""
		(layer "F.Cu")
		(at 37.3126 -175.6664 -90)
		(property "Reference" "C183"
			(at 0 0 270)
			(layer "F.SilkS")
			(hide yes)
			(effects
				(font
					(size 1.27 1.27)
				)
			)
		)
		(property "Value" "SC1KP50V2KX-1GP"
			(at 1.1811 -2.7051 270)
			(unlocked yes)
			(layer "F.Fab")
			(hide yes)
			(effects
				(font
					(size 1.016 1.016)
					(thickness 0.1524)
				)
			)
		)
		(property "Device Type" "C402H22"
			(at 1.1811 -4.2291 270)
			(unlocked yes)
			(layer "F.Fab")
			(hide yes)
			(effects
				(font
					(size 1.016 1.016)
					(thickness 0.1524)
				)
			)
		)
		(duplicate_pad_numbers_are_jumpers no)
		(fp_rect
			(start -0.4318 0.9525)
			(end 0.4318 -0.9525)
			(stroke
				(width 0)
				(type default)
			)
			(fill no)
			(layer "F.CrtYd")
		)
		(fp_rect
			(start -0.4318 0.9525)
			(end 0.4318 -0.9525)
			(stroke
				(width 0)
				(type default)
			)
			(fill no)
			(layer "F.Fab")
		)
		(pad "1" smd custom
			(at 0 -0.4445 270)
			(size 0.1524 0.1524)
			(layers "F.Cu" "F.Mask" "F.Paste")
			(net "P3V3_STBY_LL_R")
			(options
				(clearance outline)
				(anchor circle)
			)
			(primitives
				(gr_poly
					(pts
						(arc
							(start 0.3048 -0.2032)
							(mid 0.275042 -0.275042)
							(end 0.2032 -0.3048)
						)
						(arc
							(start -0.2032 -0.3048)
							(mid -0.275042 -0.275042)
							(end -0.3048 -0.2032)
						)
						(arc
							(start -0.3048 0.2032)
							(mid -0.275042 0.275042)
							(end -0.2032 0.3048)
						)
						(arc
							(start 0.2032 0.3048)
							(mid 0.275042 0.275042)
							(end 0.3048 0.2032)
						)
					)
					(width 0)
					(fill yes)
				)
			)
		)
		(pad "2" smd custom
			(at 0 0.4445 270)
			(size 0.1524 0.1524)
			(layers "F.Cu" "F.Mask" "F.Paste")
			(net "P3V3_STBY_VFB")
			(options
				(clearance outline)
				(anchor circle)
			)
			(primitives
				(gr_poly
					(pts
						(arc
							(start 0.3048 -0.2032)
							(mid 0.275042 -0.275042)
							(end 0.2032 -0.3048)
						)
						(arc
							(start -0.2032 -0.3048)
							(mid -0.275042 -0.275042)
							(end -0.3048 -0.2032)
						)
						(arc
							(start -0.3048 0.2032)
							(mid -0.275042 0.275042)
							(end -0.2032 0.3048)
						)
						(arc
							(start 0.2032 0.3048)
							(mid 0.275042 0.275042)
							(end 0.3048 0.2032)
						)
					)
					(width 0)
					(fill yes)
				)
			)
		)
	)
)
